# BASEBOARD_FAB2 (Tioga Pass) — schematic netlist excerpt (pin names and nets, part order shuffled) for the footprints in the layout excerpt that follows; sources: Cadence DE-HDL packaged netlist, KiCad conversion of Wiwynn_Tioga_Pass_MB.brd

C2N7  CAP_A  1.0UF 6.3V 10% X6S  pkg 0402V  page 131 : A = P1V05_PCH_STBY ; B = GND
C5P2  CAP  100UF 4V 20% X5R  pkg 0805  page 220 : A = PVDDQ_DEF ; B = GND
C4W3  CAP  220PF 50V 10% X7R  pkg 0402LF  page 235 : A = A_TSENSE_PVNN_PCH_TMON ; B = GND

(kicad_pcb
	(version 20260206)
	(generator "pcbnew")
	(generator_version "10.0")
	(general
		(thickness 1.6)
		(legacy_teardrops no)
	)
	(paper "A4")
	(title_block
		(title "Wiwynn_Tioga_Pass_MB.brd")
		(comment 1 "Tioga Pass / footprints 2946-2948 of 4770")
	)
	(layers
		(0 "F.Cu" signal "TOP")
		(4 "In1.Cu" signal "L2GND")
		(6 "In2.Cu" signal "L3")
		(8 "In3.Cu" signal "L4GND")
		(10 "In4.Cu" signal "L5")
		(12 "In5.Cu" signal "L6GND")
		(14 "In6.Cu" signal "L7VCC")
		(16 "In7.Cu" signal "L8VCC")
		(18 "In8.Cu" signal "L9GND")
		(20 "In9.Cu" signal "L10")
		(22 "In10.Cu" signal "L11GND")
		(24 "In11.Cu" signal "L12")
		(26 "In12.Cu" signal "L13GND")
		(2 "B.Cu" signal "BOTTOM")
		(9 "F.Adhes" user "F.Adhesive")
		(11 "B.Adhes" user "B.Adhesive")
		(13 "F.Paste" user "Package Geometry/Pastemask Top")
		(15 "B.Paste" user "Package Geometry/Pastemask Bottom")
		(5 "F.SilkS" user "Ref Des/Silkscreen Top")
		(7 "B.SilkS" user "Ref Des/Silkscreen Bottom")
		(1 "F.Mask" user "Board Geometry/Soldermask Top")
		(3 "B.Mask" user "Board Geometry/Soldermask Bottom")
		(17 "Dwgs.User" user "User.Drawings")
		(19 "Cmts.User" user "User.Comments")
		(21 "Eco1.User" user "User.Eco1")
		(23 "Eco2.User" user "User.Eco2")
		(25 "Edge.Cuts" user "Board Geometry/Outline")
		(27 "Margin" user)
		(31 "F.CrtYd" user "Package Geometry/Place Bound Top")
		(29 "B.CrtYd" user "Package Geometry/Place Bound Bottom")
		(35 "F.Fab" user "Ref Des/Assembly Top")
		(33 "B.Fab" user "Ref Des/Assembly Bottom")
	)
	(footprint ""
		(layer "B.Cu")
		(at 391.65022 -153.46172 -90)
		(property "Reference" "C4W3"
			(at 0.8382 -0.67818 270)
			(unlocked yes)
			(layer "B.SilkS")
			(effects
				(font
					(size 0.4064 0.254)
					(thickness 0.1524)
				)
				(justify left mirror)
			)
		)
		(property "Value" ""
			(at 0 0 90)
			(layer "B.Fab")
			(effects
				(font
					(size 1.27 1.27)
				)
				(justify mirror)
			)
		)
		(duplicate_pad_numbers_are_jumpers no)
		(fp_poly
			(pts
				(xy -0.3048 -0.1016) (xy -0.3048 0.9906) (xy 0.3048 0.9906) (xy 0.3048 -0.1016)
			)
			(stroke
				(width 0)
				(type default)
			)
			(fill no)
			(layer "B.CrtYd")
		)
		(fp_line
			(start -0.3048 0.9906)
			(end -0.3048 -0.1016)
			(stroke
				(width 0.1)
				(type default)
			)
			(layer "B.Fab")
		)
		(fp_line
			(start 0.3048 0.9906)
			(end -0.3048 0.9906)
			(stroke
				(width 0.1)
				(type default)
			)
			(layer "B.Fab")
		)
		(fp_line
			(start -0.3048 -0.1016)
			(end 0.3048 -0.1016)
			(stroke
				(width 0.1)
				(type default)
			)
			(layer "B.Fab")
		)
		(fp_line
			(start 0.3048 -0.1016)
			(end 0.3048 0.9906)
			(stroke
				(width 0.1)
				(type default)
			)
			(layer "B.Fab")
		)
		(pad "1" smd rect
			(at 0 0 90)
			(size 0.508 0.508)
			(layers "B.Cu" "B.Mask" "B.Paste")
			(net "A_TSENSE_PVNN_PCH_TMON")
		)
		(pad "2" smd rect
			(at 0 0.889 90)
			(size 0.508 0.508)
			(layers "B.Cu" "B.Mask" "B.Paste")
			(net "GND")
		)
		(zone
			(layer "B.Cu")
			(hatch none 0.5)
			(connect_pads
				(clearance 0)
			)
			(min_thickness 0.25)
			(keepout
				(tracks not_allowed)
				(vias allowed)
				(pads allowed)
				(copperpour not_allowed)
				(footprints allowed)
			)
			(placement
				(enabled no)
				(sheetname "")
			)
			(fill
				(thermal_gap 0.5)
				(thermal_bridge_width 0.5)
				(island_removal_mode 0)
			)
			(polygon
				(pts
					(xy 391.01522 -153.20772) (xy 391.01522 -153.71572) (xy 391.39622 -153.71572) (xy 391.39622 -153.20772)
				)
			)
		)
		(zone
			(layer "B.Cu")
			(hatch none 0.5)
			(connect_pads
				(clearance 0)
			)
			(min_thickness 0.25)
			(keepout
				(tracks allowed)
				(vias not_allowed)
				(pads allowed)
				(copperpour not_allowed)
				(footprints allowed)
			)
			(placement
				(enabled no)
				(sheetname "")
			)
			(fill
				(thermal_gap 0.5)
				(thermal_bridge_width 0.5)
				(island_removal_mode 0)
			)
			(polygon
				(pts
					(xy 391.39622 -153.20772) (xy 391.39622 -153.71572) (xy 391.01522 -153.71572) (xy 391.01522 -153.20772)
				)
			)
		)
	)
	(footprint ""
		(layer "B.Cu")
		(at 265.672824 -85.075014)
		(property "Reference" "C5P2"
			(at 0 0 0)
			(layer "B.SilkS")
			(hide yes)
			(effects
				(font
					(size 1.27 1.27)
				)
				(justify mirror)
			)
		)
		(property "Value" ""
			(at 0 0 0)
			(layer "B.Fab")
			(effects
				(font
					(size 1.27 1.27)
				)
				(justify mirror)
			)
		)
		(duplicate_pad_numbers_are_jumpers no)
		(fp_poly
			(pts
				(xy 0.7239 -0.2159) (xy -0.7239 -0.2159) (xy -0.7239 1.9939) (xy 0.7239 1.9939)
			)
			(stroke
				(width 0)
				(type default)
			)
			(fill no)
			(layer "B.CrtYd")
		)
		(fp_line
			(start -0.7239 -0.2159)
			(end 0.7239 -0.2159)
			(stroke
				(width 0.1)
				(type default)
			)
			(layer "B.Fab")
		)
		(fp_line
			(start -0.7239 1.9939)
			(end -0.7239 -0.2159)
			(stroke
				(width 0.1)
				(type default)
			)
			(layer "B.Fab")
		)
		(fp_line
			(start 0.7239 -0.2159)
			(end 0.7239 1.9939)
			(stroke
				(width 0.1)
				(type default)
			)
			(layer "B.Fab")
		)
		(fp_line
			(start 0.7239 1.9939)
			(end -0.7239 1.9939)
			(stroke
				(width 0.1)
				(type default)
			)
			(layer "B.Fab")
		)
		(pad "1" smd rect
			(at 0 0 180)
			(size 1.27 1.016)
			(layers "B.Cu" "B.Mask" "B.Paste")
			(net "PVDDQ_DEF")
		)
		(pad "2" smd rect
			(at 0 1.778 180)
			(size 1.27 1.016)
			(layers "B.Cu" "B.Mask" "B.Paste")
			(net "GND")
		)
		(zone
			(layer "B.Cu")
			(hatch none 0.5)
			(connect_pads
				(clearance 0)
			)
			(min_thickness 0.25)
			(keepout
				(tracks not_allowed)
				(vias allowed)
				(pads allowed)
				(copperpour not_allowed)
				(footprints allowed)
			)
			(placement
				(enabled no)
				(sheetname "")
			)
			(fill
				(thermal_gap 0.5)
				(thermal_bridge_width 0.5)
				(island_removal_mode 0)
			)
			(polygon
				(pts
					(xy 266.307824 -84.567014) (xy 265.037824 -84.567014) (xy 265.037824 -83.805014) (xy 266.307824 -83.805014)
				)
			)
		)
	)
	(footprint ""
		(layer "B.Cu")
		(at 394.13815 -110.25505 90)
		(property "Reference" "C2N7"
			(at 0 0 90)
			(layer "B.SilkS")
			(hide yes)
			(effects
				(font
					(size 1.27 1.27)
				)
				(justify mirror)
			)
		)
		(property "Value" ""
			(at 0 0 90)
			(layer "B.Fab")
			(effects
				(font
					(size 1.27 1.27)
				)
				(justify mirror)
			)
		)
		(duplicate_pad_numbers_are_jumpers no)
		(fp_rect
			(start 0.2794 0.9144)
			(end -0.2794 -0.1143)
			(stroke
				(width 0)
				(type default)
			)
			(fill no)
			(layer "B.CrtYd")
		)
		(fp_line
			(start 0.2794 -0.1143)
			(end -0.2794 -0.1143)
			(stroke
				(width 0.1)
				(type default)
			)
			(layer "B.Fab")
		)
		(fp_line
			(start -0.2794 -0.1143)
			(end -0.2794 0.9144)
			(stroke
				(width 0.1)
				(type default)
			)
			(layer "B.Fab")
		)
		(fp_line
			(start 0.2794 0.9144)
			(end 0.2794 -0.1143)
			(stroke
				(width 0.1)
				(type default)
			)
			(layer "B.Fab")
		)
		(fp_line
			(start -0.2794 0.9144)
			(end 0.2794 0.9144)
			(stroke
				(width 0.1)
				(type default)
			)
			(layer "B.Fab")
		)
		(pad "1" smd custom
			(at 0 0)
			(size 0.10414 0.10414)
			(layers "B.Cu" "B.Mask" "B.Paste")
			(net "P1V05_PCH_STBY")
			(options
				(clearance outline)
				(anchor circle)
			)
			(primitives
				(gr_poly
					(pts
						(xy -0.20828 -0.08636) (xy -0.20828 0.08636) (xy -0.08636 0.20828) (xy 0.086614 0.20828) (xy 0.20828 0.086614)
						(xy 0.20828 -0.08636) (xy 0.08636 -0.20828) (xy -0.08636 -0.20828)
					)
					(width 0)
					(fill yes)
				)
			)
		)
		(pad "2" smd custom
			(at 0 0.8001)
			(size 0.10414 0.10414)
			(layers "B.Cu" "B.Mask" "B.Paste")
			(net "GND")
			(options
				(clearance outline)
				(anchor circle)
			)
			(primitives
				(gr_poly
					(pts
						(xy -0.20828 -0.08636) (xy -0.20828 0.08636) (xy -0.08636 0.20828) (xy 0.086614 0.20828) (xy 0.20828 0.086614)
						(xy 0.20828 -0.08636) (xy 0.08636 -0.20828) (xy -0.08636 -0.20828)
					)
					(width 0)
					(fill yes)
				)
			)
		)
		(zone
			(layer "B.Cu")
			(hatch none 0.5)
			(connect_pads
				(clearance 0)
			)
			(min_thickness 0.25)
			(keepout
				(tracks not_allowed)
				(vias allowed)
				(pads allowed)
				(copperpour not_allowed)
				(footprints allowed)
			)
			(placement
				(enabled no)
				(sheetname "")
			)
			(fill
				(thermal_gap 0.5)
				(thermal_bridge_width 0.5)
				(island_removal_mode 0)
			)
			(polygon
				(pts
					(xy 394.3477 -110.34268) (xy 394.7287 -110.34268) (xy 394.7287 -110.16742) (xy 394.3477 -110.167166)
				)
			)
		)
		(zone
			(layer "B.Cu")
			(hatch none 0.5)
			(connect_pads
				(clearance 0)
			)
			(min_thickness 0.25)
			(keepout
				(tracks allowed)
				(vias not_allowed)
				(pads allowed)
				(copperpour not_allowed)
				(footprints allowed)
			)
			(placement
				(enabled no)
				(sheetname "")
			)
			(fill
				(thermal_gap 0.5)
				(thermal_bridge_width 0.5)
				(island_removal_mode 0)
			)
			(polygon
				(pts
					(xy 394.3477 -110.34268) (xy 394.7287 -110.34268) (xy 394.7287 -110.16742) (xy 394.3477 -110.167166)
				)
			)
		)
	)
)
